# BARRELEYE_G2-BPX24-EVT-HW-EBOM-X00_20161124-add_2nd_source_X09-20161207-Final.xls — PWA BOM (bom)
| FOXCONN TECHNOLOGY GROUP |  |  |  |  |  |  |  |  |  |  |  |  |  |  |  |  |  |  |  |
| BILL OF MATERIAL |  |  |  |  |  |  |  |  |  |  |  |  |  |  |  |  |  |  |  |
| REV OF  BOM | X09 | CUSTOMER |  | RACKSPACE |  | CUSTOMER P/N |  | PWA P/N： | PWA DESCRIPTION |  |  |  | PRODUCT CODE |  |  | PWA  REV |  | DATE |  |
| Sourcing (Single/Sole/Multi) | Critical Commodity (Y or N) | Component Class (1, 2, other) | Customer PSL (Y or N) | Line Item | Item Number | Foxconn P/N | Customer P/N | Part Description | Manufacturer  Full Name | Manufacturer  Part Number | Qty | RoHS Status | Location | CC Qual Build: | Qual by (Customer / ODM ?) | The Date of Change Part or Add 2nd Source | Configuration Identifier | Customer Comments | ODM Comments |
|  |  |  |  | 1 | 1 | 0101E1G00-000-G |  | PCB,Barreleye-G2-BPX24 EVT-X00,OSP,Red,10L,19.542*3.470,G | GCE | 0101E1G00-000-G | 1 |  | PCB |  |  |  |  |  |  |
|  |  |  |  |  | 1 | 0101E1G00-000-G |  | PCB,Barreleye-G2-BPX24 EVT-X00,OSP,Red,10L,19.542*3.470,G | FOUNDER | 0101E1G00-000-G |  |  |  |  |  |  |  |  |  |
|  |  |  |  | 2 | 2 | 62111EC00-021-G |  | ECAP,680uF,+/-20%,16V,105℃,G,SMD10*10,ESR<=80mOhm | NIPPON CHEMI-CON CORPORATION | EMZA160ADA681MJA0G | 1 |  | CE1 |  |  |  |  |  |  |
|  |  |  |  |  | 2 | 62110EH00-024-G |  | ECAP,680uF,+/-20%,16V,105_x0003_,G,SMD10X10.2,ESR<=80mOhm | PANASONIC INDUSTRIAL CO.,LTD. | EEEFK1C681P |  |  |  |  |  |  |  |  |  |
|  |  |  |  |  | 2 | 62111H200-018-G |  | ECAP,680uF,+/-20%,16V,105_x0003_,G,SMD10X10.5,ESR<=80mOhm | RUBYCON CORP. | 16TZV680M10X10.5 |  |  |  |  |  |  |  |  |  |
|  |  |  |  | 3 | 3 | 620101T02-015-G | - | CAP,100nF,+/-10%,X7R,16V,G,SMD0402 | MURATA ELEC. NORTH AMERICA | GRM155R71C104K | 93 |  | PSTC1,PFTC1,PETC1,C1,C2,C6,C8,C9,PSRC10,C10,C119,C123,C125,C129,C155,C159,C161,C165,C167,C171,C173,C177,C179,C183,C185,C189,C191,C192,C193,C194,C196,C198,C201,C207,C216,C217,C224,C225,C226,C227,C228,C229,C230,C231,C232,C233,C234,C235,C236,C237,C238,C239,C240,C241,C242,C243,C244,C245,C246,C247,C248,C249,C253,C255,C259,C261,C265,C267,C271,C273,C277,C279,C283,C285,C289,C291,C295,C297,C301,C303,C307,C309,C313,C315,C319,C321,C325,C327,C331,C333,C337,C339,C343 |  |  |  |  |  |  |
|  |  |  |  |  | 3 | 620101T00-015-G |  | CAP,100nF,+/-10%,X7R,16V,G,SMD0402 | MURATA ELEC. NORTH AMERICA | GRM155R71C104KA88D |  |  |  |  |  |  |  |  |  |
|  |  |  |  |  | 3 | 620101T00-026-G |  | CAP,100nF,+/-10%,X7R,16V,G,SMD0402 | SAMSUNG SEMICONDUCTOR | CL05B104KO5NNNC |  |  |  |  |  |  |  |  |  |
|  |  |  |  |  | 3 | 620101T00-012-G |  | CAP,100nF,+/-10%,X7R,16V,G,SMD0402 | WALSIN TECHNOLOGY CORPORATION | 0402B104K160CT |  |  |  |  |  |  |  |  |  |
|  |  |  |  | 4 | 4 | 620100A00-015-G | - | CAP,10uF,+/-10%,X5R,16V,G,SMD1206 | MURATA ELEC. NORTH AMERICA | GRM31CR61C106K | 28 |  | C3,C4,C5,C7,C120,C128,C158,C164,C170,C176,C182,C188,C252,C258,C264,C270,C276,C282,C288,C294,C300,C306,C312,C318,C324,C330,C336,C342 |  |  |  |  |  |  |
|  |  |  |  |  | 4 | 620100A03-023-G |  | CAP,10uF,+/-10%,X5R,16V,G,SMD1206 | TAIYO ELECTRIC IND.CO.LTD | EMK316BJ106KL-T |  |  |  |  |  |  |  |  |  |
|  |  |  |  |  | 4 | 620100A00-026-G |  | CAP,10uF,+/-10%,X5R,16V,G,SMD1206 | SAMSUNG SEMICONDUCTOR | CL31A106KOHNNNE |  |  |  |  |  |  |  |  |  |
|  |  |  |  | 5 | 5 | 620117N00-015-G | - | CAP,22uF,+/-10%,X5R,16V,G,SMD1206 | MURATA ELEC. NORTH AMERICA | GRM31CR61C226K | 48 |  | C121,C122,C126,C130,C156,C160,C162,C166,C168,C172,C174,C178,C180,C184,C186,C190,C250,C254,C256,C260,C262,C266,C268,C272,C274,C278,C280,C284,C286,C290,C292,C296,C298,C302,C304,C308,C310,C314,C316,C320,C322,C326,C328,C332,C334,C338,C340,C344 |  |  |  |  |  |  |
|  |  |  |  |  | 5 | 620117N00-023-G |  | CAP,22uF,+/-10%,X5R,16V,G,SMD1206 | TAIYO ELECTRIC IND.CO.LTD | EMK316BJ226KL-T |  |  |  |  |  |  |  |  |  |
|  |  |  |  |  | 5 | 620117N01-026-G |  | CAP,22uF,+/-10%,X5R,16V,G,SMD1206 | SAMSUNG SEMICONDUCTOR | CL31A226KOHNNNE |  |  |  |  |  |  |  |  |  |
|  |  |  |  | 6 | 6 | 620108H00-015-G | - | CAP,22uF,+/-20%,X5R,6.3V,G,SMD0805 | MURATA ELEC. NORTH AMERICA | GRM21BR60J226M | 24 |  | C124,C127,C157,C163,C169,C175,C181,C187,C251,C257,C263,C269,C275,C281,C287,C293,C299,C305,C311,C317,C323,C329,C335,C341 |  |  |  |  |  |  |
|  |  |  |  |  | 6 | 620108H0G-023-G |  | CAP,22uF,+/-20%,X5R,6.3V,G,SMD0805 | TAIYO ELECTRIC IND.CO.LTD | JMK212ABJ226MG-T |  |  |  |  |  |  |  |  |  |
|  |  |  |  |  | 6 | 620108H00-026-G |  | CAP,22uF,+/-20%,X5R,6.3V,G,SMD0805 | SAMSUNG SEMICONDUCTOR | CL21A226MQQNNNE |  |  |  |  |  |  |  |  |  |
|  |  |  |  | 7 | 7 | 62011AM00-015-G |  | CAP,6.8nF,+/-10%,X7R,50V,G,SMD0402 | MURATA ELEC. NORTH AMERICA | GRM155R71H682K | 1 |  | C195 |  |  |  |  |  |  |
|  |  |  |  |  | 7 | 62011AM00-026-G |  | CAP,6.8nF,+/-10%,X7R,50V,G,SMD0402 | SAMSUNG SEMICONDUCTOR | CL05B682KB5NNNC |  |  |  |  |  |  |  |  |  |
|  |  |  |  |  | 7 | 62011AM00-012-G |  | CAP,6.8nF,+/-10%,X7R,50V,G,SMD0402 | WALSIN TECHNOLOGY CORPORATION | 0402B682K500CT |  |  |  |  |  |  |  |  |  |
|  |  |  |  | 8 | 8 | 620105E00-015-G |  | CAP,1uF,+/-10%,X7R,10V,G,SMD0603 | MURATA ELEC. NORTH AMERICA | GRM188R71A105K | 2 |  | C197,C215 |  |  |  |  |  |  |
|  |  |  |  |  | 8 | 620105E00-026-G |  | CAP,1uF,+/-10%,X7R,10V,G,SMD0603 | SAMSUNG SEMICONDUCTOR | CL10B105KP8NNNC |  |  |  |  |  |  |  |  |  |
|  |  |  |  |  | 8 | 620105E01-023-G |  | CAP,1uF,+/-10%,X7R,10V,G,SMD0603 | TAIYO ELECTRIC IND.CO.LTD | LMK107B7105KA-T |  |  |  |  |  |  |  |  |  |
|  |  |  |  | 9 | 9 | 620103600-015-G | - | CAP,10nF,+/-10%,X7R,25V,G,SMD0402 | MURATA ELEC. NORTH AMERICA | GRM155R71E103K | 10 |  | C199,C202,C203,C204,C205,C218,C219,C220,C221,C222 |  |  |  |  |  |  |
|  |  |  |  |  | 9 | 620103600-026-G |  | CAP,10nF,+/-10%,X7R,25V,G,SMD0402 | SAMSUNG SEMICONDUCTOR | CL05B103KA5NNNC |  |  |  |  |  |  |  |  |  |
|  |  |  |  |  | 9 | 620103600-012-G |  | CAP,10nF,+/-10%,X7R,25V,G,SMD0402 | WALSIN TECHNOLOGY CORPORATION | 0402B103K250CT |  |  |  |  |  |  |  |  |  |
|  |  |  |  | 10 | 10 | 62010L000-015-G | - | CAP,10uF,+/-20%,X5R,6.3V,G,SMD0603 | MURATA ELEC. NORTH AMERICA | GRM188R60J106M | 2 |  | C200,C214 |  |  |  |  |  |  |
|  |  |  |  |  | 10 | 62010L000-026-G |  | CAP,10uF,+/-20%,X5R,6.3V,G,SMD0603 | SAMSUNG SEMICONDUCTOR | CL10A106MQ8NNNC |  |  |  |  |  |  |  |  |  |
|  |  |  |  |  | 10 | 62010L004-023-G |  | CAP,10uF,+/-20%,X5R,6.3V,G,SMD0603 | TAIYO ELECTRIC IND.CO.LTD | JMK107ABJ106MA-T |  |  |  |  |  |  |  |  |  |
|  |  |  |  | 11 | 11 | 62011NF01-015-G |  | CAP,2.2uF,+/-10%,X7R,25V,G,SMD0805 | MURATA ELEC. NORTH AMERICA | GRM21BR71E225K | 2 |  | C206,C223 |  |  |  |  |  |  |
|  |  |  |  |  | 11 | 62011NF00-026-G |  | CAP,2.2uF,+/-10%,X7R,25V,G,SMD0805 | SAMSUNG SEMICONDUCTOR | CL21B225KAFNNNE |  |  |  |  |  |  |  |  |  |
|  |  |  |  |  | 11 | 62011NF00-023-G |  | CAP,2.2uF,+/-10%,X7R,25V,G,SMD0805 | TAIYO ELECTRIC IND.CO.LTD | TMK212B7225KG-TR |  |  |  |  |  |  |  |  |  |
|  |  |  |  | 12 | 12 | 52110LN00-289-G |  | LED,Gre,LTST-C191KGKT,2.4V,30mA,G,SMD0603 | LITE-ON TECHNOLOGY CORPORATION | LTST-C191KGKT | 24 |  | LED37,LED39,LED49,LED51,LED53,LED55,LED57,LED59,LED61,LED63,LED65,LED67,LED69,LED71,LED73,LED75,LED77,LED79,LED81,LED83,LED85,LED87,LED89,LED91 |  |  |  |  |  |  |
|  |  |  |  | 13 | 13 | 52110A800-289-G |  | LED,Gre/Yel,LTST-C195KGJSKT,2.4V,30mA,G,SMD | LITE-ON TECHNOLOGY CORPORATION | LTST-C195KGJSKT | 24 |  | LED38,LED40,LED50,LED52,LED54,LED56,LED58,LED60,LED62,LED64,LED66,LED68,LED70,LED72,LED74,LED76,LED78,LED80,LED82,LED84,LED86,LED88,LED90,LED92 |  |  |  |  |  |  |
|  |  |  |  |  | 13 | 52110QV00-326-G |  | LED,Yel/Yel Gre,19-223/Y2G6C-A01/2T,2.4V,25mA,G,SMD | EVERLIGHT ELECTRONICS COMPANY,LTD. | 19-223/Y2G6C-A01/2T |  |  |  |  |  |  |  |  |  |
|  |  |  |  | 14 | 14 | 720101900-015-G | - | FB,60 Ohm@100MHz,+/-25%,3A,25mOhm,G,SMD0805 | MURATA ELEC. NORTH AMERICA | BLM21PG600SN1D | 1 |  | L1 |  |  |  |  |  |  |
|  |  |  |  |  | 14 | 720102E00-129-G |  | FB,60 Ohm@100MHz,+/-25%,3A,40mOhm,G,SMD0805 | MAG.LAYERS, SCIENTIFIC-TECHNICS (KUNSHAN) CO., LTD. | GMLB-201209-0060P-N8 |  |  |  |  |  |  |  |  |  |
|  |  |  |  |  | 14 | 720104100-074-G |  | FB,60 Ohm@100MHz,+/-25%,3A,30mOhm,G,SMD0805 | CHILISIN ELECTRONICS CORP. | PBY201209T-600Y-N |  |  |  |  |  |  |  |  |  |
|  |  |  |  | 15 | 15 | 72010JY00-015-G |  | FB,330 Ohm@100MHz,+/-25%,1.5A,70mOhm,G,SMD0603 | MURATA ELEC. NORTH AMERICA | BLM18SG331TN1D | 2 |  | L2,L4 |  |  |  |  |  |  |
|  |  |  |  |  | 15 | 72010JB00-016-G |  | FB,330 Ohm@100MHz,+/-25%,1.5A,G,80mOhm,SMD0603 | TDK ELECTRONICS EUROPE GMBH | MPZ1608S331AT |  |  |  |  |  |  |  |  |  |
|  |  |  |  | 16 | 16 | 71020NS00-967-G |  | OSC,25MHz,+/-25ppm,3.3V,15pF,G,SMD | SaRonix-eCERA Corporation | FK2500025 | 1 |  | OSC1 |  |  |  |  |  |  |
|  |  |  |  |  | 16 | 710209J00-100-G |  | OSC,25MHz,+/-25ppm,3.3V,15pF,,-10_x0003_~70_x0003_,SMD,G | TXC CORPORATION | 7X25000008 |  |  |  |  |  |  |  |  |  |
|  |  |  |  | 17 | 17 | 62120HT00-024-G |  | ECAP,SPEA,100uF,+/-20%,10V,105C,G,SMD2816,ESR<=40mOhm | PANASONIC INDUSTRIAL CO.,LTD. | EEFCX1A101R | 3 |  | PSTCE3003,PFTCE3003,PETCE3003 |  |  |  |  |  |  |
|  |  |  |  | 18 | 18 | 62012PT00-015-G |  | CAP,22uF,+/-20%,X6S,16V,G,SMD0805 | MURATA ELEC. NORTH AMERICA | GRM21BC81C226M | 14 |  | PSTC2,PFTC2,PETC2,PSTC3,PFTC3,PETC3,PSRC7,PSRC8,PSRC11,PSRC12,PSRC15,PSTC3000,PFTC3000,PETC3000 |  |  |  |  |  |  |
|  |  |  |  |  | 18 | 62012PT00-023-G |  | CAP,22uF,+/-20%,X6S,16V,G,SMD0805 | TAIYO ELECTRIC IND.CO.LTD | EDK212BC6226MG-T |  |  |  |  |  |  |  |  |  |
|  |  |  |  | 19 | 19 | 62012T500-015-G |  | CAP,22uF,+/-20%,X7S,25V,G,SMD1206 | MURATA ELEC. NORTH AMERICA | GRM31CC71E226ME11L | 41 |  | PSRC2,PSTC6,PFTC6,PETC6,PSTC7,PFTC7,PETC7,PSTC8,PFTC8,PETC8,PSTC9,PFTC9,PETC9,PSRC17,PSTC3005,PFTC3005,PETC3005,PSTC3006,PFTC3006,PETC3006,PSTC3007,PFTC3007,PETC3007,PSTC3010,PFTC3010,PETC3010,PSTC3011,PFTC3011,PETC3011,PSTC3012,PFTC3012,PETC3012,PSTC3013,PFTC3013,PETC3013,PFTC3014,PETC3014,PFTC3015,PETC3015,PFTC3016,PETC3016 |  |  |  |  |  |  |
|  |  |  |  | 20 | 20 | 620103U00-015-G | - | CAP,470pF,+/-10%,X7R,50V,G,SMD0402 | MURATA ELEC. NORTH AMERICA | GRM155R71H471K | 3 |  | PSTC10,PFTC10,PETC10 |  |  |  |  |  |  |
|  |  |  |  |  | 20 | 620103U00-012-G |  | CAP,470pF,+/-10%,X7R,50V,G,SMD0402 | WALSIN TECHNOLOGY CORPORATION | 0402B471K500CT |  |  |  |  |  |  |  |  |  |
|  |  |  |  |  | 20 | 620103U00-026-G |  | CAP,470pF,+/-10%,X7R,50V,G,SMD0402 | SAMSUNG SEMICONDUCTOR | CL05B471KB5NNNC |  |  |  |  |  |  |  |  |  |
|  |  |  |  |  | 20 | 620103U00-023-G |  | CAP,470pF,+/-10%,X7R,50V,G,SMD0402 | TAIYO ELECTRIC IND.CO.LTD | UMK105B7471KV-F |  |  |  |  |  |  |  |  |  |
|  |  |  |  | 21 | 21 | 62010FG00-015-G | - | CAP,3.3pF,+/-0.25pF,NPO(C0G),50V,G,SMD0402 | MURATA ELEC. NORTH AMERICA | GRM1555C1H3R3C | 3 |  | PSTC11,PFTC11,PETC11 |  |  |  |  |  |  |
|  |  |  |  |  | 21 | 62010FG08-012-G |  | CAP,3.3pF,+/-0.25pF,NPO(C0G),50V,G,SMD0402 | WALSIN TECHNOLOGY CORPORATION | 0402N3R3C500CT |  |  |  |  |  |  |  |  |  |
|  |  |  |  |  | 21 | 62010FG00-026-G |  | CAP,3.3pF,+/-0.25pF,NPO(C0G),50V,G,SMD0402 | SAMSUNG SEMICONDUCTOR | CL05C3R3CB5ANNC |  |  |  |  |  |  |  |  |  |
|  |  |  |  | 22 | 22 | 620107L00-015-G | - | CAP,2.2nF,+/-10%,X7R,50V,G,SMD0402 | MURATA ELEC. NORTH AMERICA | GRM155R71H222K | 3 |  | PSTC12,PFTC12,PETC12 |  |  |  |  |  |  |
|  |  |  |  |  | 22 | 620107L00-012-G |  | CAP,2.2nF,+/-10%,X7R,50V,G,SMD0402 | WALSIN TECHNOLOGY CORPORATION | 0402B222K500CT |  |  |  |  |  |  |  |  |  |
|  |  |  |  |  | 22 | 620107L00-026-G |  | CAP,2.2nF,+/-10%,X7R,50V,G,SMD0402 | SAMSUNG SEMICONDUCTOR | CL05B222KB5NNNC |  |  |  |  |  |  |  |  |  |
|  |  |  |  |  | 22 | 620107L03-023-G |  | CAP,2.2nF,+/-10%,X7R,50V,G,SMD0402 | TAIYO ELECTRIC IND.CO.LTD | UMK105B7222KV-F |  |  |  |  |  |  |  |  |  |
|  |  |  |  | 23 | 23 | 62012A400-015-G | - | CAP,100nF,+/-10%,X7R,25V,G,SMD0402 | MURATA ELEC. NORTH AMERICA | GRM155R71E104KE14D | 8 |  | PSRC1,PSRC6,PSTC3002,PFTC3002,PETC3002,PSTC3008,PFTC3008,PETC3008 |  |  |  |  |  |  |
|  |  |  |  |  | 23 | 62012A400-023-G |  | CAP,100nF,+/-10%,X7R,25V,G,SMD0402 | TAIYO ELECTRIC IND.CO.LTD | TMK105B7104KV-FR |  |  |  |  |  |  |  |  |  |
|  |  |  |  |  | 23 | 62012A400-026-G |  | CAP,100nF,+/-10%,X7R,25V,G,SMD0402 | SAMSUNG SEMICONDUCTOR | CL05B104KA5NNNC |  |  |  |  |  |  |  |  |  |
|  |  |  |  |  | 23 | 62012A400-012-G |  | CAP,100nF,+/-10%,X7R,25V,G,SMD0402 | WALSIN TECHNOLOGY CORPORATION | 0402B104K250CT |  |  |  |  |  |  |  |  |  |
|  |  |  |  | 24 | 24 | 62012T300-015-G |  | CAP,1uF,+/-10%,X7S,25V,G,SMD0402 | MURATA ELEC. NORTH AMERICA | GRM155C71E105KE11D | 4 |  | PSRC4,PSTC3003,PFTC3003,PETC3003 |  |  |  |  |  |  |
|  |  |  |  | 25 | 25 | 62012GG00-015-G |  | CAP,10uF,+/-10%,X7S,25V,G,SMD0805 | MURATA ELEC. NORTH AMERICA | GRM21BC71E106K | 7 |  | PSRC3,PSTC3004,PFTC3004,PETC3004,PSTC3009,PFTC3009,PETC3009 |  |  |  |  |  |  |
|  |  |  |  |  | 25 | 62012GG00-012-G |  | CAP,10uF,+/-10%,X7S,25V,G,SMD0805 | WALSIN | 0805A106K250CT |  |  |  |  |  |  |  |  |  |
|  |  |  |  | 26 | 26 | 630335M00-088-G |  | IND,820nH@100KHz,+/-20%,13A,8mOhm,SHLD,G,SMD | COOPER BUSSMANN, INC. | HCM0703-R82-R | 3 |  | PSTL1,PFTL1,PETL1 |  |  |  |  |  |  |
|  |  |  |  | 27 | 27 | 630341400-088-G |  | IND,22nH@1MHz,+/-20%,19A,368uOhm,SHLD,G,SMD | COOPER BUSSMANN, INC. | FP0404R1-R022-R | 3 |  | PSTL2,PFTL2,PETL2 |  |  |  |  |  |  |
|  |  |  |  | 28 | 28 | 61010LA00-017-G | - | RES,4.7KOhm,+/-1%,1/16W,G,SMD0402 | KOA SPEER ELECTRONICS, INC. | RK73H1ETTP4701F | 3 |  | PSTR1,PFTR1,PETR1 |  |  |  |  |  |  |
|  |  |  |  |  | 28 | 61010LA00-011-G |  | RES,4.7KOhm,+/-1%,1/16W,G,SMD0402 | YAGEO CORPORATION COMPONENT | RC0402FR-074K7L |  |  |  |  |  |  |  |  |  |
|  |  |  |  |  | 28 | 61010LA00-012-G |  | RES,4.7KOhm,+/-1%,1/16W,G,SMD0402 | WALSIN TECHNOLOGY CORPORATION | WR04X4701FTL |  |  |  |  |  |  |  |  |  |
|  |  |  |  |  | 28 | 61010LA00-044-G |  | RES,4.7KOhm,+/-1%,1/16W,G,SMD0402 | TA-I TECHNOLOGY CO., LTD | RM04FTN4701 |  |  |  |  |  |  |  |  |  |
|  |  |  |  | 29 | 29 | 610107A00-017-G | - | RES,0 Ohm,+/-5%,1/16W,G,SMD0402 | KOA SPEER ELECTRONICS, INC. | RK73Z1ETTP | 60 |  | PSTR2,PFTR2,PETR2,R5,PSTR7,PFTR7,PETR7,R8,PSTR8,PFTR8,PETR8,PSRR9,R10,PSTR14,PFTR14,PETR14,PSRR15,PSRR18,PSTR22,PSRR22,PFTR22,PETR22,R316,R325,R405,R421,R437,R453,R469,R485,R511,R568,R569,R570,R571,R611,R627,R643,R659,R675,R691,R707,R723,R739,R755,R771,R787,R803,R819,R835,R851,PSTR3001,PFTR3001,PETR3001,PSTR3002,PFTR3002,PETR3002,PSTR3003,PFTR3003,PETR3003 |  |  |  |  |  |  |
|  |  |  |  |  | 29 | 610107A00-011-G |  | RES,0 Ohm,+/-5%,1/16W,G,SMD0402 | YAGEO CORPORATION COMPONENT | RC0402JR-070RL |  |  |  |  |  |  |  |  |  |
|  |  |  |  |  | 29 | 610107A00-012-G |  | RES,0 Ohm,+/-5%,1/16W,G,SMD0402 | WALSIN TECHNOLOGY CORPORATION | WR04X000PTL |  |  |  |  |  |  |  |  |  |
|  |  |  |  |  | 29 | 610107A00-044-G |  | RES,0 Ohm,+/-5%,1/16W,G,SMD0402 | TA-I TECHNOLOGY CO., LTD | RM04JTN0 |  |  |  |  |  |  |  |  |  |
|  |  |  |  |  | 29 | 610107A00-024-G |  | RES,0 Ohm,+/-5%,1/16W,G,SMD0402 | PANASONIC INDUSTRIAL CO.,LTD. | ERJ2GE0R00X |  |  |  |  |  |  |  |  |  |
|  |  |  |  |  | 29 | 610107A00-029-G |  | RES,0 Ohm,+/-5%,1/16W,G,SMD0402 | VISHAY ENTER TECHNO LOGY.INC | CRCW04020000Z0ED |  |  |  |  |  |  |  |  |  |
|  |  |  |  | 30 | 30 | 61011HA00-017-G |  | RES,1 Ohm,+/-1%,1/16W,G,SMD0402 | KOA SPEER ELECTRONICS, INC. | RK73H1ETTP1R00F | 1 |  | PSRR5 |  |  |  |  |  |  |
|  |  |  |  |  | 30 | 61011HA00-012-G |  | RES,1 Ohm,+/-1%,1/16W,G,SMD0402 | WALSIN TECHNOLOGY CORPORATION | WR04W1R00FTL |  |  |  |  |  |  |  |  |  |
|  |  |  |  |  | 30 | 61011HA00-011-G |  | RES,1 Ohm,+/-1%,1/16W,G,SMD0402 | YAGEO CORPORATION COMPONENT | RC0402FR-071RL |  |  |  |  |  |  |  |  |  |
|  |  |  |  |  | 30 | 61011HA00-044-G |  | RES,1 Ohm,+/-1%,1/16W,G,SMD0402 | TA-I TECHNOLOGY CO., LTD | RM04FTN1R00 |  |  |  |  |  |  |  |  |  |
|  |  |  |  |  | 30 | 61011HA00-029-G |  | RES,1 Ohm,+/-1%,1/16W,G,SMD0402 | VISHAY ENTER TECHNO LOGY.INC | CRCW04021R00FNED |  |  |  |  |  |  |  |  |  |
|  |  |  |  | 31 | 31 | 61100QD00-017-G |  | RES,787 Ohm,+/-0.1%,1/16W,G,SMD0402 | KOA SPEER ELECTRONICS, INC. | RN731ETTP7870B25 | 3 |  | PSTR5,PFTR5,PETR5 |  |  |  |  |  |  |
|  |  |  |  |  | 31 | 61100QD00-012-G |  | RES,787 Ohm,+/-0.1%,1/16W,G,SMD0402 | WALSIN TECHNOLOGY CORPORATION | WF04U7870BTL |  |  |  |  |  |  |  |  |  |
|  |  |  |  |  | 31 | 61100QD00-011-G |  | RES,787 Ohm,+/-0.1%,1/16W,G,SMD0402 | YAGEO CORPORATION COMPONENT | RT0402BRD07787RL |  |  |  |  |  |  |  |  |  |
|  |  |  |  | 32 | 32 | 61100SU00-017-G |  | RES,105 Ohm,+/-0.1%,1/16W,G,SMD0402 | KOA SPEER ELECTRONICS, INC. | RN731ETTP1050B25 | 3 |  | PSTR6,PFTR6,PETR6 |  |  |  |  |  |  |
|  |  |  |  |  | 32 | 61100SU00-012-G |  | RES,105 Ohm,+/-0.1%,1/16W,G,SMD0402 | WALSIN TECHNOLOGY CORPORATION | WF04U1050BTL |  |  |  |  |  |  |  |  |  |
|  |  |  |  |  | 32 | 61100SU00-011-G |  | RES,105 Ohm,+/-0.1%,1/16W,G,SMD0402 | YAGEO CORPORATION COMPONENT | RT0402BRD07105RL |  |  |  |  |  |  |  |  |  |
|  |  |  |  | 33 | 33 | 61011BD00-017-G | - | RES,46.4KOhm,+/-1%,1/16W,G,SMD0402 | KOA SPEER ELECTRONICS, INC. | RK73H1ETTP4642F | 3 |  | PSTR9,PFTR9,PETR9 |  |  |  |  |  |  |
|  |  |  |  |  | 33 | 61011BD00-012-G |  | RES,46.4KOhm,+/-1%,1/16W,G,SMD0402 | WALSIN TECHNOLOGY CORPORATION | WR04X4642FTL |  |  |  |  |  |  |  |  |  |
|  |  |  |  |  | 33 | 61011BD00-011-G |  | RES,46.4KOhm,+/-1%,1/16W,G,SMD0402 | YAGEO CORPORATION COMPONENT | RC0402FR-0746K4L |  |  |  |  |  |  |  |  |  |
|  |  |  |  |  | 33 | 61011BD00-044-G |  | RES,46.4KOhm,+/-1%,1/16W,G,SMD0402 | TA-I TECHNOLOGY CO., LTD | RM04FTN4642 |  |  |  |  |  |  |  |  |  |
|  |  |  |  | 34 | 34 | 610124U00-017-G | - | RES,7.87KOhm,+/-1%,1/16W,G,SMD0402 | KOA SPEER ELECTRONICS, INC. | RK73H1ETTP7871F | 3 |  | PSTR10,PFTR10,PETR10 |  |  |  |  |  |  |
|  |  |  |  |  | 34 | 610124U00-012-G |  | RES,7.87KOhm,+/-1%,1/16W,G,SMD0402 | WALSIN TECHNOLOGY CORPORATION | WR04X7871FTL |  |  |  |  |  |  |  |  |  |
|  |  |  |  |  | 34 | 610124U00-011-G |  | RES,7.87KOhm,+/-1%,1/16W,G,SMD0402 | YAGEO CORPORATION COMPONENT | RC0402FR-077K87L |  |  |  |  |  |  |  |  |  |
|  |  |  |  |  | 34 | 610124U00-044-G |  | RES,7.87KOhm,+/-1%,1/16W,G,SMD0402 | TA-I TECHNOLOGY CO., LTD | RM04FTN7871 |  |  |  |  |  |  |  |  |  |
|  |  |  |  | 35 | 35 | 610112J00-017-G | - | RES,200 Ohm,+/-1%,1/16W,G,SMD0402 | KOA SPEER ELECTRONICS, INC. | RK73H1ETTP2000F | 3 |  | PSTR11,PFTR11,PETR11 |  |  |  |  |  |  |
|  |  |  |  |  | 35 | 610112J00-012-G |  | RES,200 Ohm,+/-1%,1/16W,G,SMD0402 | WALSIN TECHNOLOGY CORPORATION | WR04X2000FTL |  |  |  |  |  |  |  |  |  |
|  |  |  |  |  | 35 | 610112J00-011-G |  | RES,200 Ohm,+/-1%,1/16W,G,SMD0402 | YAGEO CORPORATION COMPONENT | RC0402FR-07200RL |  |  |  |  |  |  |  |  |  |
|  |  |  |  |  | 35 | 610112J00-044-G |  | RES,200 Ohm,+/-1%,1/16W,G,SMD0402 | TA-I TECHNOLOGY CO., LTD | RM04FTN2000 |  |  |  |  |  |  |  |  |  |
|  |  |  |  |  | 35 | 610112J00-029-G |  | RES,200 Ohm,+/-1%,1/16W,G,SMD0402 | VISHAY ENTER TECHNO LOGY.INC | CRCW0402200RFKED |  |  |  |  |  |  |  |  |  |
|  |  |  |  |  | 35 | 610112J00-024-G |  | RES,200 Ohm,+/-1%,1/16W,G,SMD0402 | PANASONIC INDUSTRIAL CO.,LTD. | ERJ2RKF2000X |  |  |  |  |  |  |  |  |  |
|  |  |  |  | 36 | 36 | 61011JY00-017-G | - | RES,39.2KOhm,+/-1%,1/16W,G,SMD0402 | KOA SPEER ELECTRONICS, INC. | RK73H1ETTP3922F | 3 |  | PSTR15,PFTR15,PETR15 |  |  |  |  |  |  |
|  |  |  |  |  | 36 | 61011JY00-012-G |  | RES,39.2KOhm,+/-1%,1/16W,G,SMD0402 | WALSIN TECHNOLOGY CORPORATION | WR04X3922FTL |  |  |  |  |  |  |  |  |  |
|  |  |  |  |  | 36 | 61011JY00-011-G |  | RES,39.2KOhm,+/-1%,1/16W,G,SMD0402 | YAGEO CORPORATION COMPONENT | RC0402FR-0739K2L |  |  |  |  |  |  |  |  |  |
|  |  |  |  |  | 36 | 61011JY00-044-G |  | RES,39.2KOhm,+/-1%,1/16W,G,SMD0402 | TA-I TECHNOLOGY CO., LTD | RM04FTN3922 |  |  |  |  |  |  |  |  |  |
|  |  |  |  |  | 36 | 61011JY00-029-G |  | RES,39.2KOhm,+/-1%,1/16W,G,SMD0402 | VISHAY ENTER TECHNO LOGY.INC | CRCW040239K2FKED |  |  |  |  |  |  |  |  |  |
|  |  |  |  | 37 | 37 | 32013P700-238-G |  | IC,Regulator,IR3448MTRPBF,ADJ,16A,G,PQFN-33,SMD | INTERNATIONAL RECTIFIER | IR3448MTRPBF | 3 |  | PSTU1,PFTU1,PETU1 |  |  |  |  |  |  |
|  |  |  |  | 38 | 38 | 62012P100-015-G |  | CAP,2.2uF,+/-20%,X7S,10V,G,SMD0402 | MURATA ELEC. NORTH AMERICA | GRM155C71A225M | 1 |  | PSRC5 |  |  |  |  |  |  |
|  |  |  |  |  | 38 | 62012P100-012-G |  | CAP,2.2uF,+/-20%,X7S,10V,G,SMD0402 | WALSIN | 0402A225M100CT |  |  |  |  |  |  |  |  |  |
|  |  |  |  | 39 | 39 | 620105U00-015-G | - | CAP,220pF,+/-10%,X7R,50V,G,SMD0402 | MURATA ELEC. NORTH AMERICA | GRM155R71H221K | 1 |  | PSRC14 |  |  |  |  |  |  |
|  |  |  |  |  | 39 | 620105U00-012-G |  | CAP,220pF,+/-10%,X7R,50V,G,SMD0402 | WALSIN TECHNOLOGY CORPORATION | 0402B221K500CT |  |  |  |  |  |  |  |  |  |
|  |  |  |  |  | 39 | 620105U00-026-G |  | CAP,220pF,+/-10%,X7R,50V,G,SMD0402 | SAMSUNG SEMICONDUCTOR | CL05B221KB5NNNC |  |  |  |  |  |  |  |  |  |
|  |  |  |  | 40 | 40 | 62012H100-015-G |  | CAP,10uF,+/-20%,X6S,10V,G,SMD0603 | MURATA ELEC. NORTH AMERICA | GRM188C81A106M | 1 |  | PSRC16 |  |  |  |  |  |  |
|  |  |  |  |  | 40 | 62012H100-023-G |  | CAP,10uF,+/-20%,X6S,10V,G,SMD0603 | TAIYO ELECTRIC IND.CO.LTD | LMK107BC6106MA-T |  |  |  |  |  |  |  |  |  |
|  |  |  |  |  | 40 | 62012H100-026-G |  | CAP,10uF,+/-20%,X6S,10V,G,SMD0603 | SAMSUNG SEMICONDUCTOR | CL10X106MP8NRNC |  |  |  |  |  |  |  |  |  |
|  |  |  |  | 41 | 41 | 72010RE00-015-G |  | FB,26 Ohm@100MHz,+/-25%,6A,7mOhm,G,SMD0603 | MURATA ELEC. NORTH AMERICA | BLM18KG260TN1D | 1 |  | PSRL1 |  |  |  |  |  |  |
|  |  |  |  |  | 41 | 72010SJ00-059-G |  | FB,Multilayer,10mOhm,26Ohm@100MHz,+/-25%,6A,,SMD0603,G | TAI-TECH ADVANCED ELECTRONICS CO., LTD. | HCB1608KF-260T60 |  |  |  |  |  |  |  |  |  |
|  |  |  |  | 42 | 42 | 63032PP00-088-G |  | IND,4.7uH@100KHz,+/-20%,5.5A,40mOhm,SHLD,G,SMD | COOPER BUSSMANN, INC. | HCM0703-4R7-R | 1 |  | PSRL2 |  |  |  |  |  |  |
|  |  |  |  | 43 | 43 | 610117D00-017-G | - | RES,13.3KOhm,+/-1%,1/16W,G,SMD0402 | KOA SPEER ELECTRONICS, INC. | RK73H1ETTP1332F | 1 |  | PSRR1 |  |  |  |  |  |  |
|  |  |  |  |  | 43 | 610117D00-012-G |  | RES,13.3KOhm,+/-1%,1/16W,G,SMD0402 | WALSIN TECHNOLOGY CORPORATION | WR04X1332FTL |  |  |  |  |  |  |  |  |  |
|  |  |  |  |  | 43 | 610117D00-011-G |  | RES,13.3KOhm,+/-1%,1/16W,G,SMD0402 | YAGEO CORPORATION COMPONENT | RC0402FR-0713K3L |  |  |  |  |  |  |  |  |  |
|  |  |  |  |  | 43 | 610117D00-044-G |  | RES,13.3KOhm,+/-1%,1/16W,G,SMD0402 | TA-I TECHNOLOGY CO., LTD | RM04FTN1332 |  |  |  |  |  |  |  |  |  |
|  |  |  |  | 44 | 44 | 610114S00-017-G | - | RES,4.99KOhm,+/-1%,1/16W,G,SMD0402 | KOA SPEER ELECTRONICS, INC. | RK73H1ETTP4991F | 1 |  | PSRR3 |  |  |  |  |  |  |
|  |  |  |  |  | 44 | 610114S00-012-G |  | RES,4.99KOhm,+/-1%,1/16W,G,SMD0402 | WALSIN TECHNOLOGY CORPORATION | WR04X4991FTL |  |  |  |  |  |  |  |  |  |
|  |  |  |  |  | 44 | 610114S00-011-G |  | RES,4.99KOhm,+/-1%,1/16W,G,SMD0402 | YAGEO CORPORATION COMPONENT | RC0402FR-074K99L |  |  |  |  |  |  |  |  |  |
|  |  |  |  |  | 44 | 610114S00-044-G |  | RES,4.99KOhm,+/-1%,1/16W,G,SMD0402 | TA-I TECHNOLOGY CO., LTD | RM04FTN4991 |  |  |  |  |  |  |  |  |  |
|  |  |  |  |  | 44 | 610114S00-024-G |  | RES,4.99KOhm,+/-1%,1/16W,G,SMD0402 | PANASONIC INDUSTRIAL CO.,LTD. | ERJ2RKF4991X |  |  |  |  |  |  |  |  |  |
|  |  |  |  | 45 | 45 | 61010G500-017-G | - | RES,10KOhm,+/-1%,1/16W,G,SMD0402 | KOA SPEER ELECTRONICS, INC. | RK73H1ETTP1002F | 1 |  | PSRR6 |  |  |  |  |  |  |
|  |  |  |  |  | 45 | 61010G500-011-G |  | RES,10KOhm,+/-1%,1/16W,G,SMD0402 | YAGEO CORPORATION COMPONENT | RC0402FR-0710KL |  |  |  |  |  |  |  |  |  |
|  |  |  |  |  | 45 | 61010G500-012-G |  | RES,10KOhm,+/-1%,1/16W,G,SMD0402 | WALSIN TECHNOLOGY CORPORATION | WR04X1002FTL |  |  |  |  |  |  |  |  |  |
|  |  |  |  |  | 45 | 61010G500-044-G |  | RES,10KOhm,+/-1%,1/16W,G,SMD0402 | TA-I TECHNOLOGY CO., LTD | RM04FTN1002 |  |  |  |  |  |  |  |  |  |
|  |  |  |  |  | 45 | 61010G500-029-G |  | RES,10KOhm,+/-1%,1/16W,G,SMD0402 | VISHAY ENTER TECHNO LOGY.INC | CRCW040210K0FKED |  |  |  |  |  |  |  |  |  |
|  |  |  |  |  | 45 | 61010G500-024-G |  | RES,10KOhm,+/-1%,1/16W,G,SMD0402 | PANASONIC INDUSTRIAL CO.,LTD. | ERJ2RKF1002X |  |  |  |  |  |  |  |  |  |
|  |  |  |  | 46 | 46 | 611004M00-017-G |  | RES,16.5KOhm,+/-0.1%,1/16W,G,SMD0402 | KOA SPEER ELECTRONICS, INC. | RN731ETTP1652B25 | 1 |  | PSRR17 |  |  |  |  |  |  |
|  |  |  |  |  | 46 | 611004M00-024-G |  | RES,16.5KOhm,+/-0.1%,1/16W,G,SMD0402 | PANASONIC INDUSTRIAL CO.,LTD. | ERA2AEB1652X |  |  |  |  |  |  |  |  |  |
|  |  |  |  | 47 | 47 | 61100YB00-017-G |  | RES,2.94KOhm,+/-0.1%,1/16W,G,SMD0402 | KOA SPEER ELECTRONICS, INC. | RN731ETTP2941B25 | 1 |  | PSRR19 |  |  |  |  |  |  |
|  |  |  |  | 48 | 48 | 32013PD00-238-G |  | IC,Regulator,IR3883MTRPbF,ADJ,3A,G,QFN-16,SMD | INTERNATIONAL RECTIFIER | IR3883MTRPBF | 1 |  | PSRU1 |  |  |  |  |  |  |
|  |  |  |  | 49 | 49 | 510504M00-237-G |  | MOS N/N,BSS138DW-7-F,50V,0.2A,3.5ohm@10V,G,SOT363-6,SMD | DIODES INEORPORATION | BSS138DW-7-F | 25 |  | QN19,QN20,QN25,QN26,QN27,QN28,QN29,QN30,QN31,QN33,QN34,QN35,QN36,QN37,QN38,QN39,QN40,QN41,QN42,QN43,QN44,QN45,QN46,QN47,QN48 |  |  |  |  |  |  |
|  |  |  |  |  | 49 | 510507900-223-G |  | MOS N/N,NTJD4001NT1G,30V,0.25A,1.5ohm@4V,G,SOT363-6,SMD | ON SEMICONDUCTOR CORP | NTJD4001NT1G |  |  |  |  |  |  |  |  |  |
|  |  |  |  | 50 | 50 | 510301D00-223-G |  | MOS N,BSS138LT1G,50V,0.2A,3.5ohm@5V,G,SOT23-3,SMD | ON SEMICONDUCTOR CORP | BSS138LT1G | 24 |  | Q1,Q2,Q3,Q4,Q5,Q6,Q7,Q8,Q9,Q10,Q11,Q12,Q13,Q14,Q15,Q16,Q17,Q18,Q19,Q20,Q21,Q22,Q23,Q24 |  |  |  |  |  |  |
|  |  |  |  |  | 50 | 510309C00-237-G |  | MOS N,BSS138-7-F,50V,0.2A,3.5ohm@10V,G,SOT23-3,SMD | DIODES INEORPORATION | BSS138-7-F |  |  |  |  |  |  |  |  |  |
|  |  |  |  |  | 50 | 510302R00-185-G |  | MOS N,BSS138,50V,0.22A,6ohm@4.5V,G,SOT23-3,SMD | FAIRCHILD SEMICONDUCTOR CORP | BSS138 |  |  |  |  |  |  |  |  |  |
|  |  |  |  |  | 50 | 51030A800-221-G |  | MOS N,BSS138N,60V,0.23A,6ohm@4.5V,G,SOT23-3,SMD | INFINEON TECHNOLOGIES CORP. | BSS138N |  |  |  |  |  |  |  |  |  |
|  |  |  |  | 51 | 51 | 61011H500-017-G | - | RES,22 Ohm,+/-1%,1/16W,G,SMD0402 | KOA SPEER ELECTRONICS, INC. | RK73H1ETTP22R0F | 10 |  | R1,R14,R504,R509,R531,R550,R552,R572,R868,R869 |  |  |  |  |  |  |
|  |  |  |  |  | 51 | 61011H500-044-G |  | RES,22 Ohm,+/-1%,1/16W,G,SMD0402 | TA-I TECHNOLOGY CO., LTD | RM04FTN22R0 |  |  |  |  |  |  |  |  |  |
|  |  |  |  |  | 51 | 61011H500-011-G |  | RES,22 Ohm,+/-1%,1/16W,G,SMD0402 | YAGEO CORPORATION COMPONENT | RC0402FR-0722RL |  |  |  |  |  |  |  |  |  |
|  |  |  |  |  | 51 | 61011H500-012-G |  | RES,22 Ohm,+/-1%,1/16W,G,SMD0402 | WALSIN TECHNOLOGY CORPORATION | WR04X22R0FTL |  |  |  |  |  |  |  |  |  |
|  |  |  |  |  | 51 | 61011H500-024-G |  | RES,22 Ohm,+/-1%,1/16W,G,SMD0402 | PANASONIC INDUSTRIAL CO.,LTD. | ERJ2RKF22R0X |  |  |  |  |  |  |  |  |  |
|  |  |  |  | 52 | 52 | 61011MQ00-017-G | - | RES,4.75KOhm,+/-1%,1/16W,G,SMD0402 | KOA SPEER ELECTRONICS, INC. | RK73H1ETTP4751F | 2 |  | R2,R4 |  |  |  |  |  |  |
|  |  |  |  |  | 52 | 61011MQ00-011-G |  | RES,4.75KOhm,+/-1%,1/16W,G,SMD0402 | YAGEO CORPORATION COMPONENT | RC0402FR-074K75L |  |  |  |  |  |  |  |  |  |
|  |  |  |  |  | 52 | 61011MQ00-012-G |  | RES,4.75KOhm,+/-1%,1/16W,G,SMD0402 | WALSIN TECHNOLOGY CORPORATION | WR04X4751FTL |  |  |  |  |  |  |  |  |  |
|  |  |  |  |  | 52 | 61011MQ00-044-G |  | RES,4.75KOhm,+/-1%,1/16W,G,SMD0402 | TA-I TECHNOLOGY CO., LTD | RM04FTN4751 |  |  |  |  |  |  |  |  |  |
|  |  |  |  | 53 | 53 | 610107B00-017-G |  | RES,4.7KOhm,+/-5%,1/16W,G,SMD0402 | KOA SPEER ELECTRONICS, INC. | RK73B1ETTP472J | 196 |  | R6,R7,R9,R16,R17,R18,R309,R310,R312,R322,R323,R324,R328,R331,R333,R337,R338,R340,R408,R411,R413,R417,R418,R420,R424,R427,R429,R433,R434,R436,R440,R443,R445,R448,R450,R452,R456,R460,R461,R465,R466,R468,R472,R475,R477,R480,R482,R484,R488,R492,R493,R497,R498,R500,R503,R505,R506,R507,R510,R512,R513,R514,R516,R527,R528,R541,R546,R547,R548,R549,R553,R555,R556,R557,R559,R560,R587,R588,R589,R590,R591,R592,R593,R594,R595,R596,R597,R598,R599,R600,R601,R602,R603,R604,R605,R606,R607,R608,R609,R610,R614,R617,R619,R622,R624,R626,R630,R634,R635,R639,R640,R642,R646,R649,R651,R654,R656,R658,R662,R666,R667,R671,R672,R674,R678,R681,R683,R686,R688,R690,R694,R698,R699,R703,R704,R706,R710,R713,R715,R718,R720,R722,R726,R730,R731,R735,R736,R738,R742,R745,R747,R750,R752,R754,R758,R762,R763,R767,R768,R770,R774,R777,R779,R782,R784,R786,R790,R794,R795,R799,R800,R802,R806,R809,R811,R814,R816,R818,R822,R826,R827,R831,R832,R834,R838,R841,R843,R846,R848,R850,R854,R858,R859,R863,R864,R866 |  |  |  |  |  |  |
|  |  |  |  |  | 53 | 610107B00-011-G |  | RES,4.7KOhm,+/-5%,1/16W,G,SMD0402 | YAGEO CORPORATION COMPONENT | RC0402JR-074K7L |  |  |  |  |  |  |  |  |  |
|  |  |  |  |  | 53 | 610107B00-012-G |  | RES,4.7KOhm,+/-5%,1/16W,G,SMD0402 | WALSIN TECHNOLOGY CORPORATION | WR04X472JTL |  |  |  |  |  |  |  |  |  |
|  |  |  |  |  | 53 | 610107B00-044-G |  | RES,4.7KOhm,+/-5%,1/16W,G,SMD0402 | TA-I TECHNOLOGY CO., LTD | RM04JTN472 |  |  |  |  |  |  |  |  |  |
|  |  |  |  |  | 53 | 610107B00-024-G |  | RES,4.7KOhm,+/-5%,1/16W,G,SMD0402 | PANASONIC INDUSTRIAL CO.,LTD. | ERJ2GEJ472X |  |  |  |  |  |  |  |  |  |
|  |  |  |  |  | 53 | 610107B00-029-G |  | RES,4.7KOhm,+/-5%,1/16W,G,SMD0402 | VISHAY ENTER TECHNO LOGY.INC | CRCW04024K70JNED |  |  |  |  |  |  |  |  |  |
|  |  |  |  | 54 | 54 | 61010JY00-017-G | - | RES,220 Ohm,+/-5%,1/16W,G,SMD0402 | KOA SPEER ELECTRONICS, INC. | RK73B1ETTP221J | 2 |  | R12,R15 |  |  |  |  |  |  |
|  |  |  |  |  | 54 | 61010JY00-011-G |  | RES,220 Ohm,+/-5%,1/16W,G,SMD0402 | YAGEO CORPORATION COMPONENT | RC0402JR-07220RL |  |  |  |  |  |  |  |  |  |
|  |  |  |  |  | 54 | 61010JY00-012-G |  | RES,220 Ohm,+/-5%,1/16W,G,SMD0402 | WALSIN TECHNOLOGY CORPORATION | WR04X221JTL |  |  |  |  |  |  |  |  |  |
|  |  |  |  |  | 54 | 61010JY00-044-G |  | RES,220 Ohm,+/-5%,1/16W,G,SMD0402 | TA-I TECHNOLOGY CO., LTD | RM04JTN221 |  |  |  |  |  |  |  |  |  |
|  |  |  |  | 55 | 55 | 61010BG00-017-G |  | RES,100 Ohm,+/-1%,1/10W,G,SMD0603 | KOA SPEER ELECTRONICS, INC. | RK73H1JTTD1000F | 72 |  | R313,R317,R319,R330,R332,R335,R410,R412,R415,R426,R428,R431,R442,R444,R447,R458,R459,R463,R474,R476,R479,R490,R491,R495,R616,R618,R621,R632,R633,R637,R648,R650,R653,R664,R665,R669,R680,R682,R685,R696,R697,R701,R712,R714,R717,R728,R729,R733,R744,R746,R749,R760,R761,R765,R776,R778,R781,R792,R793,R797,R808,R810,R813,R824,R825,R829,R840,R842,R845,R856,R857,R861 |  |  |  |  |  |  |
|  |  |  |  |  | 55 | 61010BG00-012-G |  | RES,100 Ohm,+/-1%,1/10W,G,SMD0603 | WALSIN TECHNOLOGY CORPORATION | WR06X1000FTL |  |  |  |  |  |  |  |  |  |
|  |  |  |  |  | 55 | 61010BG00-011-G |  | RES,100 Ohm,+/-1%,1/10W,G,SMD0603 | YAGEO CORPORATION COMPONENT | RC0603FR-07100RL |  |  |  |  |  |  |  |  |  |
|  |  |  |  | 56 | 56 | 61011QA00-017-G | - | RES,24KOhm,+/-5%,1/16W,G,SMD0402 | KOA SPEER ELECTRONICS, INC. | RK73B1ETTP243J | 24 |  | R314,R327,R407,R423,R439,R454,R471,R486,R613,R628,R645,R660,R677,R692,R709,R724,R741,R756,R773,R788,R805,R820,R837,R852 |  |  |  |  |  |  |
|  |  |  |  |  | 56 | 61011QA00-011-G |  | RES,24KOhm,+/-5%,1/16W,G,SMD0402 | YAGEO CORPORATION COMPONENT | RC0402JR-0724KL |  |  |  |  |  |  |  |  |  |
|  |  |  |  |  | 56 | 61011QA00-012-G |  | RES,24KOhm,+/-5%,1/16W,G,SMD0402 | WALSIN TECHNOLOGY CORPORATION | WR04X243JTL |  |  |  |  |  |  |  |  |  |
|  |  |  |  |  | 56 | 61011QA00-044-G |  | RES,24KOhm,+/-5%,1/16W,G,SMD0402 | TA-I TECHNOLOGY CO., LTD | RM04JTN243 |  |  |  |  |  |  |  |  |  |
|  |  |  |  | 57 | 57 | 610115Y00-017-G | - | RES,16.2KOhm,+/-1%,1/16W,G,SMD0402 | KOA SPEER ELECTRONICS, INC. | RK73H1ETTP1622F | 24 |  | R318,R326,R406,R422,R438,R455,R470,R487,R612,R629,R644,R661,R676,R693,R708,R725,R740,R757,R772,R789,R804,R821,R836,R853 |  |  |  |  |  |  |
|  |  |  |  |  | 57 | 610115Y00-011-G |  | RES,16.2KOhm,+/-1%,1/16W,G,SMD0402 | YAGEO CORPORATION COMPONENT | RC0402FR-0716K2L |  |  |  |  |  |  |  |  |  |
|  |  |  |  |  | 57 | 610115Y00-012-G |  | RES,16.2KOhm,+/-1%,1/16W,G,SMD0402 | WALSIN TECHNOLOGY CORPORATION | WR04X1622FTL |  |  |  |  |  |  |  |  |  |
|  |  |  |  |  | 57 | 610115Y00-044-G |  | RES,16.2KOhm,+/-1%,1/16W,G,SMD0402 | TA-I TECHNOLOGY CO., LTD | RM04FTN1622 |  |  |  |  |  |  |  |  |  |
|  |  |  |  |  | 57 | 610115Y00-024-G |  | RES,16.2KOhm,+/-1%,1/16W,G,SMD0402 | PANASONIC INDUSTRIAL CO.,LTD. | ERJ2RKF1622X |  |  |  |  |  |  |  |  |  |
|  |  |  |  |  | 57 | 610115Y00-029-G |  | RES,16.2KOhm,+/-1%,1/16W,G,SMD0402 | VISHAY ENTER TECHNO LOGY.INC | CRCW040216K2FKED |  |  |  |  |  |  |  |  |  |
|  |  |  |  | 58 | 58 | 610113A00-017-G | - | RES,2.2 Ohm,+/-5%,1/2W,G,SMD1210 | KOA SPEER ELECTRONICS, INC. | RK73B2ETTD2R2J | 48 |  | R320,R321,R334,R336,R414,R416,R430,R432,R446,R449,R462,R464,R478,R481,R494,R496,R620,R623,R636,R638,R652,R655,R668,R670,R684,R687,R700,R702,R716,R719,R732,R734,R748,R751,R764,R766,R780,R783,R796,R798,R812,R815,R828,R830,R844,R847,R860,R862 |  |  |  |  |  |  |
|  |  |  |  |  | 58 | 610113A00-012-G |  | RES,2.2 Ohm,+/-5%,1/2W,G,SMD1210 | WALSIN TECHNOLOGY CORPORATION | WF10P2R2JTL |  |  |  |  |  |  |  |  |  |
|  |  |  |  |  | 58 | 610113A00-011-G |  | RES,2.2 Ohm,+/-5%,1/2W,G,SMD1210 | YAGEO CORPORATION COMPONENT | RC1210JR-072R2L |  |  |  |  |  |  |  |  |  |
|  |  |  |  | 59 | 59 | 610114J00-017-G | - | RES,2KOhm,+/-1%,1/16W,G,SMD0402 | KOA SPEER ELECTRONICS, INC. | RK73H1ETTP2001F | 5 |  | R501,R502,R508,R544,R545 |  |  |  |  |  |  |
|  |  |  |  |  | 59 | 610114J00-011-G |  | RES,2KOhm,+/-1%,1/16W,G,SMD0402 | YAGEO CORPORATION COMPONENT | RC0402FR-072KL |  |  |  |  |  |  |  |  |  |
|  |  |  |  |  | 59 | 610114J00-012-G |  | RES,2KOhm,+/-1%,1/16W,G,SMD0402 | WALSIN TECHNOLOGY CORPORATION | WR04X2001FTL |  |  |  |  |  |  |  |  |  |
|  |  |  |  |  | 59 | 610114J00-044-G |  | RES,2KOhm,+/-1%,1/16W,G,SMD0402 | TA-I TECHNOLOGY CO., LTD | RM04FTN2001 |  |  |  |  |  |  |  |  |  |
|  |  |  |  |  | 59 | 610114J00-024-G |  | RES,2KOhm,+/-1%,1/16W,G,SMD0402 | PANASONIC INDUSTRIAL CO.,LTD. | ERJ2RKF2001X |  |  |  |  |  |  |  |  |  |
|  |  |  |  |  | 59 | 610114J00-029-G |  | RES,2KOhm,+/-1%,1/16W,G,SMD0402 | VISHAY ENTER TECHNO LOGY.INC | CRCW04022K00FKED |  |  |  |  |  |  |  |  |  |
|  |  |  |  | 60 | 60 | 610100T00-017-G |  | RES,1KOhm,+/-5%,1/16W,G,SMD0402 | KOA SPEER ELECTRONICS, INC. | RK73B1ETTP102J | 15 |  | R515,R517,R518,R519,R521,R522,R523,R524,R558,R561,R562,R564,R565,R566,R567 |  |  |  |  |  |  |
|  |  |  |  |  | 60 | 610100T00-012-G |  | RES,1KOhm,+/-5%,1/16W,G,SMD0402 | WALSIN TECHNOLOGY CORPORATION | WR04X102JTL |  |  |  |  |  |  |  |  |  |
|  |  |  |  |  | 60 | 610100T00-011-G |  | RES,1KOhm,+/-5%,1/16W,G,SMD0402 | YAGEO CORPORATION COMPONENT | RC0402JR-071KL |  |  |  |  |  |  |  |  |  |
|  |  |  |  |  | 60 | 610100T00-044-G |  | RES,1KOhm,+/-5%,1/16W,G,SMD0402 | TA-I TECHNOLOGY CO., LTD | RM04JTN102 |  |  |  |  |  |  |  |  |  |
|  |  |  |  |  | 60 | 610100T00-024-G |  | RES,1KOhm,+/-5%,1/16W,G,SMD0402 | PANASONIC INDUSTRIAL CO.,LTD. | ERJ2GEJ102X |  |  |  |  |  |  |  |  |  |
|  |  |  |  | 61 | 61 | 61010L300-017-G | - | RES,1KOhm,+/-1%,1/16W,G,SMD0402 | KOA SPEER ELECTRONICS, INC. | RK73H1ETTP1001F | 2 |  | R525,R532 |  |  |  |  |  |  |
|  |  |  |  |  | 61 | 61010L300-011-G |  | RES,1KOhm,+/-1%,1/16W,G,SMD0402 | YAGEO CORPORATION COMPONENT | RC0402FR-071KL |  |  |  |  |  |  |  |  |  |
|  |  |  |  |  | 61 | 61010L300-012-G |  | RES,1KOhm,+/-1%,1/16W,G,SMD0402 | WALSIN TECHNOLOGY CORPORATION | WR04X1001FTL |  |  |  |  |  |  |  |  |  |
|  |  |  |  |  | 61 | 61010L300-044-G |  | RES,1KOhm,+/-1%,1/16W,G,SMD0402 | TA-I TECHNOLOGY CO., LTD | RM04FTN1001 |  |  |  |  |  |  |  |  |  |
|  |  |  |  |  | 61 | 61010L300-024-G |  | RES,1KOhm,+/-1%,1/16W,G,SMD0402 | PANASONIC INDUSTRIAL CO.,LTD. | ERJ2RKF1001X |  |  |  |  |  |  |  |  |  |
|  |  |  |  |  | 61 | 61010L300-029-G |  | RES,1KOhm,+/-1%,1/16W,G,SMD0402 | VISHAY ENTER TECHNO LOGY.INC | CRCW04021K00FKED |  |  |  |  |  |  |  |  |  |
|  |  |  |  | 62 | 62 | 61010PS00-017-G | - | RES,200KOhm,+/-1%,1/16W,G,SMD0402 | KOA SPEER ELECTRONICS, INC. | RK73H1ETTP2003F | 2 |  | R526,R533 |  |  |  |  |  |  |
|  |  |  |  |  | 62 | 61010PS00-012-G |  | RES,200KOhm,+/-1%,1/16W,G,SMD0402 | WALSIN TECHNOLOGY CORPORATION | WR04X2003FTL |  |  |  |  |  |  |  |  |  |
|  |  |  |  |  | 62 | 61010PS00-011-G |  | RES,200KOhm,+/-1%,1/16W,G,SMD0402 | YAGEO CORPORATION COMPONENT | RC0402FR-07200KL |  |  |  |  |  |  |  |  |  |
|  |  |  |  |  | 62 | 61010PS00-044-G |  | RES,200KOhm,+/-1%,1/16W,G,SMD0402 | TA-I TECHNOLOGY CO., LTD | RM04FTN2003 |  |  |  |  |  |  |  |  |  |
|  |  |  |  | 63 | 63 | 61011BW00-017-G |  | RES,1.2KOhm,+/-1%,1/16W,G,SMD0402 | KOA SPEER ELECTRONICS, INC. | RK73H1ETTP1201F | 2 |  | R529,R535 |  |  |  |  |  |  |
|  |  |  |  |  | 63 | 61011BW00-012-G |  | RES,1.2KOhm,+/-1%,1/16W,G,SMD0402 | WALSIN TECHNOLOGY CORPORATION | WR04X1201FTL |  |  |  |  |  |  |  |  |  |
|  |  |  |  |  | 63 | 61011BW00-011-G |  | RES,1.2KOhm,+/-1%,1/16W,G,SMD0402 | YAGEO CORPORATION COMPONENT | RC0402FR-071K2L |  |  |  |  |  |  |  |  |  |
|  |  |  |  |  | 63 | 61011BW00-044-G |  | RES,1.2KOhm,+/-1%,1/16W,G,SMD0402 | TA-I TECHNOLOGY CO., LTD | RM04FTN1201 |  |  |  |  |  |  |  |  |  |
|  |  |  |  | 64 | 64 | 610116V00-017-G | - | RES,232KOhm,+/-1%,1/16W,G,SMD0402 | KOA SPEER ELECTRONICS, INC. | RK73H1ETTP2323F | 1 |  | R530 |  |  |  |  |  |  |
|  |  |  |  |  | 64 | 610116V00-012-G |  | RES,232KOhm,+/-1%,1/16W,G,SMD0402 | WALSIN TECHNOLOGY CORPORATION | WR04X2323FTL |  |  |  |  |  |  |  |  |  |
|  |  |  |  |  | 64 | 610116V00-011-G |  | RES,232KOhm,+/-1%,1/16W,G,SMD0402 | YAGEO CORPORATION COMPONENT | RC0402FR-07232KL |  |  |  |  |  |  |  |  |  |
|  |  |  |  |  | 64 | 610116V00-044-G |  | RES,232KOhm,+/-1%,1/16W,G,SMD0402 | TA-I TECHNOLOGY CO., LTD | RM04FTN2323 |  |  |  |  |  |  |  |  |  |
|  |  |  |  | 65 | 65 | 610116B00-017-G |  | RES,180KOhm,+/-1%,1/16W,G,SMD0402 | KOA SPEER ELECTRONICS, INC. | RK73H1ETTP1803F | 1 |  | R534 |  |  |  |  |  |  |
|  |  |  |  |  | 65 | 610116B00-012-G |  | RES,180KOhm,+/-1%,1/16W,G,SMD0402 | WALSIN TECHNOLOGY CORPORATION | WR04X1803FTL |  |  |  |  |  |  |  |  |  |
|  |  |  |  |  | 65 | 610116B00-011-G |  | RES,180KOhm,+/-1%,1/16W,G,SMD0402 | YAGEO CORPORATION COMPONENT | RC0402FR-07180KL |  |  |  |  |  |  |  |  |  |
|  |  |  |  |  | 65 | 610116B00-044-G |  | RES,180KOhm,+/-1%,1/16W,G,SMD0402 | TA-I TECHNOLOGY CO., LTD | RM04FTN1803 |  |  |  |  |  |  |  |  |  |
|  |  |  |  | 66 | 66 | 61011BQ00-017-G | - | RES,2.2 Ohm,+/-5%,1/16W,G,SMD0402 | KOA SPEER ELECTRONICS, INC. | RK73B1ETTP2R2J | 2 |  | R540,R583 |  |  |  |  |  |  |
|  |  |  |  |  | 66 | 61011BQ00-011-G |  | RES,2.2 Ohm,+/-5%,1/16W,G,SMD0402 | YAGEO CORPORATION COMPONENT | RC0402JR-072R2L |  |  |  |  |  |  |  |  |  |
|  |  |  |  |  | 66 | 61011BQ00-012-G |  | RES,2.2 Ohm,+/-5%,1/16W,G,SMD0402 | WALSIN TECHNOLOGY CORPORATION | WR04X2R2JTL |  |  |  |  |  |  |  |  |  |
|  |  |  |  |  | 66 | 61011BQ00-044-G |  | RES,2.2 Ohm,+/-5%,1/16W,G,SMD0402 | TA-I TECHNOLOGY CO., LTD | RM04JTN2R2 |  |  |  |  |  |  |  |  |  |
|  |  |  |  | 67 | 67 | 610108300-017-G | - | RES,0 Ohm,+/-5%,1/10W,G,SMD0603 | KOA SPEER ELECTRONICS, INC. | RK73Z1JTTD | 2 |  | R542,R585 |  |  |  |  |  |  |
|  |  |  |  |  | 67 | 610108300-011-G |  | RES,0 Ohm,+/-5%,1/10W,G,SMD0603 | YAGEO CORPORATION COMPONENT | RC0603JR-070RL |  |  |  |  |  |  |  |  |  |
|  |  |  |  |  | 67 | 610108300-012-G |  | RES,0 Ohm,+/-5%,1/10W,G,SMD0603 | WALSIN TECHNOLOGY CORPORATION | WR06X000PTL |  |  |  |  |  |  |  |  |  |
|  |  |  |  |  | 67 | 610108300-044-G |  | RES,0 Ohm,+/-5%,1/10W,G,SMD0603 | TA-I TECHNOLOGY CO., LTD | RM06JTN0 |  |  |  |  |  |  |  |  |  |
|  |  |  |  |  | 67 | 610108300-024-G |  | RES,0 Ohm,+/-5%,1/10W,G,SMD0603 | PANASONIC INDUSTRIAL CO.,LTD. | ERJ3GEY0R00V |  |  |  |  |  |  |  |  |  |
|  |  |  |  | 68 | 68 | 61010FE00-017-G | - | RES,100 Ohm,+/-1%,1/16W,G,SMD0402 | KOA SPEER ELECTRONICS, INC. | RK73H1ETTP1000F | 1 |  | R543 |  |  |  |  |  |  |
|  |  |  |  |  | 68 | 61010FE00-011-G |  | RES,100 Ohm,+/-1%,1/16W,G,SMD0402 | YAGEO CORPORATION COMPONENT | RC0402FR-07100RL |  |  |  |  |  |  |  |  |  |
|  |  |  |  |  | 68 | 61010FE00-012-G |  | RES,100 Ohm,+/-1%,1/16W,G,SMD0402 | WALSIN TECHNOLOGY CORPORATION | WR04X1000FTL |  |  |  |  |  |  |  |  |  |
|  |  |  |  |  | 68 | 61010FE00-044-G |  | RES,100 Ohm,+/-1%,1/16W,G,SMD0402 | TA-I TECHNOLOGY CO., LTD | RM04FTN1000 |  |  |  |  |  |  |  |  |  |
|  |  |  |  | 69 | 69 | 620108000-015-G | - | CAP,100pF,+/-5%,NPO(C0G),50V,G,SMD0402 | MURATA ELEC. NORTH AMERICA | GRM1555C1H101J | 3 |  | PSTC4,PFTC4,PETC4 |  |  |  |  |  |  |
|  |  |  |  |  | 69 | 62010800A-012-G |  | CAP,100pF,+/-5%,NPO(C0G),50V,G,SMD0402 | WALSIN | 0402N101J500CT |  |  |  |  |  |  |  |  |  |
|  |  |  |  |  | 69 | 620108000-026-G |  | CAP,100pF,+/-5%,NPO(C0G),50V,G,SMD0402 | SAMSUNG SEMICONDUCTOR | CL05C101JB5NNNC |  |  |  |  |  |  |  |  |  |
|  |  |  |  |  | 69 | 620108000-023-G |  | CAP,100pF,+/-5%,NPO(C0G),50V,G,SMD0402 | TAIYO ELECTRIC IND.CO.LTD | UMK105CG101JV-F |  |  |  |  |  |  |  |  |  |
|  |  |  |  | 70 | 70 | 310101400-031-G | - | IC,Gate&Inverter,74LVC1G08GW,1.65~5.5V,G,SOT353-5,SMD | NXP SEMICONDUCTORS | 74LVC1G08GW | 2 |  | U_AND1,U_AND2 |  |  |  |  |  |  |
|  |  |  |  |  | 70 | 310102100-183-G |  | IC,Gate&Inverter,SN74LVC1G08DCKR,1.65~5.5V,G,SOT323-5,SMD | TEXAS INSTRUMENTS | SN74LVC1G08DCKR |  |  |  |  |  |  |  |  |  |
|  |  |  |  |  | 70 | 310103J00-223-G |  | IC,Gate&Inverter,NL17SZ08DFT2G,1.65~5.5V,G,SOT353-5,SMD | ON SEMICONDUCTOR CORP | NL17SZ08DFT2G |  |  |  |  |  |  |  |  |  |
|  |  |  |  | 71 | 71 | 41040HW00-191-G |  | EEPROM,AT24C02D-SSHM-T,1.7~3.6V,2K,I2C,G,SOIC-8,SMD | ATMEL CORPORATION | AT24C02D-SSHM-T | 1 |  | U_BP_FRU1 |  |  |  |  |  |  |
|  |  |  |  |  | 71 | 410401W00-214-G |  | EEPROM,M24C02-WMN6TP,2.5~5.5V,256*8,I2C,G,SOIC-8,SMD | STMICROELECTRONICS | M24C02-WMN6TP |  |  |  |  |  |  |  |  |  |
|  |  |  |  |  | 71 | 41040CW00-232-G |  | EEPROM,24AA024-I/SN,1.7~5.5V,2K,I2C,G,SOIC-8,SMD | MICROCHIP TECHNOLOGY INC | 24AA024-I/SN |  |  |  |  |  |  |  |  |  |
|  |  |  |  | 72 | 72 | 311004800-031-G |  | IC,Translator,PCA9617ADPJ,0.8~5.5V,2.2~5.5V,G,TSSOP-8,SMD | NXP SEMICONDUCTORS | PCA9617ADPJ | 1 |  | U_I2C_RE1 |  |  |  |  |  |  |
|  |  |  |  |  | 72 | 311004V00-223-G |  | Logic IC,Translator,PCA9617ADMR2G,Vcca=0.8V~5.5V,Vccb=2.2V~5.5V,102ns,Micro8,8P,G | ON SEMICONDUCTOR CORP | PCA9617ADMR2G |  |  |  |  |  |  |  |  |  |
|  |  |  |  |  | 72 | 311004K00-183-G |  | Logic IC,Translator,TCA9617ADGKR,Vcca=0.8V~5.5V;Vccb=2.2V~5.5V,250ns,VSSOP,8P,G | TEXAS INSTRUMENTS | TCA9617ADGKR |  |  |  |  |  |  |  |  |  |
|  |  |  |  |  | 72 | 311004U00-252-G |  | Logic IC,Translator,PI6ULS5V9617AUEX,Vcca=0.8V~5.5V,Vccb=2.2V~5.5V,102ns,MSOP,8P,G | PERICOM | PI6ULS5V9617AUEX |  |  |  |  |  |  |  |  |  |
|  |  |  |  | 73 | 73 | 32022WB00-173-G |  | IC,Power Controller,MAX6420UK16+T,G,SOT-23-5P,SMD | MAXIM INTEGRATED PRODUCTS, INC. | MAX6420UK16+T | 1 |  | U_RESET1 |  |  |  |  |  |  |
|  |  |  |  | 74 | 74 | 21081NC00-432-G |  | IC,LSI,500021009,A2,G,TFBGA-141,SMD | LSI LOGIC CORPORATION | 500021009 | 2 |  | U_SF1,U_SF2 |  |  |  |  |  |  |
|  |  |  |  | 75 | 75 | 32040J800-183-G |  | IC,Temp Sensor,TMP75AIDGKR,N/A,G,MSOP-8,SMD | TEXAS INSTRUMENTS | TMP75AIDGKR | 1 |  | U_TMP1 |  |  |  |  |  |  |
|  |  |  |  |  | 75 | 32040PJ00-223-G |  | IC,Temperature Sensor,NCT75DMR2G,G,MSOP-8,SMD | ON SEMICONDUCTOR CORP | NCT75DMR2G |  |  |  |  |  |  |  |  |  |
|  |  |  |  | 76 | 76 | 310700500-183-G |  | IC,Decoder&Encoder,PCA9306DCUR,0~5V,G,VSSOP-8,SMD | TEXAS INSTRUMENTS | PCA9306DCUR | 2 |  | U1,U2 |  |  |  |  |  |  |
|  |  |  |  |  | 76 | 311002900-031-G |  | IC,Translator,PCA9306DC1,1.0~3.6V,1.8~5.5V,G,VSSOP-8,SMD | NXP SEMICONDUCTORS | PCA9306DC1 |  |  |  |  |  |  |  |  |  |
|  |  |  |  | 77 | 77 | 310102400-183-G | - | IC,Gate&Inverter,SN74AHC1G32DBVR,2~5.5V,G,SOT23-5,SMD | TEXAS INSTRUMENTS | SN74AHC1G32DBVR | 24 |  | U5,U6,U7,U8,U9,U10,U11,U12,U13,U14,U15,U16,U17,U18,U19,U20,U21,U22,U23,U24,U25,U26,U27,U28 |  |  |  |  |  |  |
|  |  |  |  |  | 77 | 310106R00-185-G |  | IC,Gate&Inverter,NC7S32M5X,2~6V,G,SOT23-5,SMD | FAIRCHILD SEMICONDUCTOR CORP | NC7S32M5X |  |  |  |  |  |  |  |  |  |
|  |  |  |  |  | 77 | 310106U00-031-G |  | IC,Gate&Inverter,74AHC1G32GV,2~5.5V,G,SC74A-5,SMD | NXP SEMICONDUCTORS | 74AHC1G32GV |  |  |  |  |  |  |  |  |  |
|  |  |  |  | 78 | 78 | 2A5910Q00-HYM-G |  | SMT NUT,CARBON STEEL,G,FIVETECH,82-059-01-022-01-RL | Fivetech Technology Inc. | 82-059-01-022-01-RL | 8 |  | H1,H2,H3,H4,H7,H8,H9,H10 |  |  |  |  |  |  |
|  |  |  |  |  | 78 | 2A5914300-G44-G |  | Nut,CARBON STEEL,TIN Plating,G,PEM,YSMTSO-47670-ET | PennEngineering Fastening | YSMTSO-47670-ET |  |  |  |  |  |  |  |  |  |
|  |  |  |  | 79 | 79 | 340718900-245-G |  | CONN,SAS,V/T,0.6mm,30u,G,SMD-74 | AMPHENOL SHANGHAI CORP. | U10-B074-260T | 3 |  | JSAS1,JSAS2,JSAS3 |  |  |  |  |  |  |
|  |  |  |  | 80 | 80 | 3406AKN00-317-G |  | CONN,Header,Power,2X7,V/T,Bla,3mm,G,SMD-14 | MOLEX INCORPORATED | 43045-1418 | 1 |  | J_BP_PWR1 |  |  |  |  |  |  |
|  |  |  |  | 81 | 81 | 340655900-245-G | - | CONN,Header,WTB,1X4,R/A,Whi,1mm,G,SMD-4 | AMPHENOL SHANGHAI CORP. | G846A04100Y1EU | 1 |  | J_LED1 |  |  |  |  |  |  |
|  |  |  |  |  | 81 | 34066NA00-32M-G |  | CONN,Header,WTB,1X4,R/A,Whi,1mm,G,SMD-4 | BELLWETHER ELECTRONIC CORP. | 80012-0427 |  |  |  |  |  |  |  |  |  |
|  |  |  |  | 82 | 82 | 34070V200-317-G | - | CONN,SAS,V/T,Bla,1.27mm,30u,G,SMD-29 | MOLEX INCORPORATED | 78728-0002 | 24 |  | J_SASDRV01,J_SASDRV02,J_SASDRV03,J_SASDRV04,J_SASDRV05,J_SASDRV06,J_SASDRV07,J_SASDRV08,J_SASDRV09,J_SASDRV10,J_SASDRV11,J_SASDRV12,J_SASDRV13,J_SASDRV14,J_SASDRV15,J_SASDRV16,J_SASDRV17,J_SASDRV18,J_SASDRV19,J_SASDRV20,J_SASDRV21,J_SASDRV22,J_SASDRV23,J_SASDRV00 |  |  |  |  |  |  |
|  |  |  |  |  | 82 | 34070VA00-245-G |  | CONN,SAS,V/T,Bla,0.8mm,30u,G,SMD-29 | AMPHENOL SHANGHAI CORP. | SAS-F313-014-1-TR |  |  |  |  |  |  |  |  |  |
|  |  |  |  |  | 82 | 340712V00-G78-G |  | CONN,SAS,V/T,Bla,0.8mm,30u,G,SMD-29 | FCI CONNECTORS HONGKONG LTD. | 10125550-001C-TRLF |  |  |  |  |  |  |  |  |  |
